(kicad_pcb
	(version 20260206)
	(generator "pcbnew")
	(generator_version "10.0")
	(general
		(thickness 1.6)
		(legacy_teardrops no)
	)
	(paper "A4")
	(title_block
		(title "4HDD Backplane_Layout.brd")
		(comment 1 "Tioga Pass / footprints 27-34 of 97")
	)
	(layers
		(0 "F.Cu" signal "TOP")
		(4 "In1.Cu" signal "L2GND")
		(6 "In2.Cu" signal "L3")
		(8 "In3.Cu" signal "L4")
		(10 "In4.Cu" signal "L5GND")
		(2 "B.Cu" signal "BOTTOM")
		(9 "F.Adhes" user "F.Adhesive")
		(11 "B.Adhes" user "B.Adhesive")
		(13 "F.Paste" user "Package Geometry/Pastemask Top")
		(15 "B.Paste" user "Package Geometry/Pastemask Bottom")
		(5 "F.SilkS" user "Ref Des/Silkscreen Top")
		(7 "B.SilkS" user "Ref Des/Silkscreen Bottom")
		(1 "F.Mask" user "Board Geometry/Soldermask Top")
		(3 "B.Mask" user "Board Geometry/Soldermask Bottom")
		(17 "Dwgs.User" user "User.Drawings")
		(19 "Cmts.User" user "User.Comments")
		(21 "Eco1.User" user "User.Eco1")
		(23 "Eco2.User" user "User.Eco2")
		(25 "Edge.Cuts" user "Board Geometry/Outline")
		(27 "Margin" user)
		(31 "F.CrtYd" user "Package Geometry/Place Bound Top")
		(29 "B.CrtYd" user "Package Geometry/Place Bound Bottom")
		(35 "F.Fab" user "Ref Des/Assembly Top")
		(33 "B.Fab" user "Ref Des/Assembly Bottom")
	)
	(footprint ""
		(layer "F.Cu")
		(at 118.57609 -56.962802 -90)
		(property "Reference" "R4"
			(at 0 0 270)
			(layer "F.SilkS")
			(hide yes)
			(effects
				(font
					(size 1.27 1.27)
				)
			)
		)
		(property "Value" "10R3F-GP"
			(at -0.0254 -2.5146 270)
			(unlocked yes)
			(layer "F.Fab")
			(hide yes)
			(effects
				(font
					(size 1.016 1.016)
					(thickness 0.1524)
				)
			)
		)
		(property "Device Type" "R603H22"
			(at -0.0254 -4.0386 270)
			(unlocked yes)
			(layer "F.Fab")
			(hide yes)
			(effects
				(font
					(size 1.016 1.016)
					(thickness 0.1524)
				)
			)
		)
		(duplicate_pad_numbers_are_jumpers no)
		(fp_line
			(start -0.4826 0)
			(end -0.2032 0)
			(stroke
				(width 0.2032)
				(type default)
			)
			(layer "F.SilkS")
		)
		(fp_line
			(start 0.2032 0)
			(end 0.4826 0)
			(stroke
				(width 0.2032)
				(type default)
			)
			(layer "F.SilkS")
		)
		(fp_rect
			(start -0.5842 1.3335)
			(end 0.5842 -1.3335)
			(stroke
				(width 0)
				(type default)
			)
			(fill no)
			(layer "F.CrtYd")
		)
		(fp_rect
			(start -0.5842 1.3335)
			(end 0.5842 -1.3335)
			(stroke
				(width 0)
				(type default)
			)
			(fill no)
			(layer "F.Fab")
		)
		(pad "1" smd custom
			(at 0 -0.762 270)
			(size 0.2159 0.2159)
			(layers "F.Cu" "F.Mask" "F.Paste")
			(net "P5V_SW_R")
			(options
				(clearance outline)
				(anchor circle)
			)
			(primitives
				(gr_poly
					(pts
						(arc
							(start -0.3302 -0.4318)
							(mid -0.402042 -0.402042)
							(end -0.4318 -0.3302)
						)
						(arc
							(start -0.4318 0.3302)
							(mid -0.402042 0.402042)
							(end -0.3302 0.4318)
						)
						(arc
							(start 0.3302 0.4318)
							(mid 0.402042 0.402042)
							(end 0.4318 0.3302)
						)
						(arc
							(start 0.4318 -0.3302)
							(mid 0.402042 -0.402042)
							(end 0.3302 -0.4318)
						)
					)
					(width 0)
					(fill yes)
				)
			)
		)
		(pad "2" smd custom
			(at 0 0.762 270)
			(size 0.2159 0.2159)
			(layers "F.Cu" "F.Mask" "F.Paste")
			(net "5V_PRE_0")
			(options
				(clearance outline)
				(anchor circle)
			)
			(primitives
				(gr_poly
					(pts
						(arc
							(start -0.3302 -0.4318)
							(mid -0.402042 -0.402042)
							(end -0.4318 -0.3302)
						)
						(arc
							(start -0.4318 0.3302)
							(mid -0.402042 0.402042)
							(end -0.3302 0.4318)
						)
						(arc
							(start 0.3302 0.4318)
							(mid 0.402042 0.402042)
							(end 0.4318 0.3302)
						)
						(arc
							(start 0.4318 -0.3302)
							(mid 0.402042 -0.402042)
							(end 0.3302 -0.4318)
						)
					)
					(width 0)
					(fill yes)
				)
			)
		)
	)
	(footprint ""
		(layer "F.Cu")
		(at 139.999974 -61.699902)
		(property "Reference" "H2"
			(at 0 0 0)
			(layer "F.SilkS")
			(hide yes)
			(effects
				(font
					(size 1.27 1.27)
				)
			)
		)
		(property "Value" "HOLET217B237R166-GP"
			(at -5.08 -0.4572 0)
			(unlocked yes)
			(layer "F.Fab")
			(hide yes)
			(effects
				(font
					(size 1.016 1.016)
					(thickness 0.1524)
				)
			)
		)
		(property "Device Type" "HOLET217B237R166"
			(at -5.08 -1.9812 0)
			(unlocked yes)
			(layer "F.Fab")
			(hide yes)
			(effects
				(font
					(size 1.016 1.016)
					(thickness 0.1524)
				)
			)
		)
		(duplicate_pad_numbers_are_jumpers no)
		(fp_poly
			(pts
				(arc
					(start 3.3147 0)
					(mid -3.3147 0)
					(end 3.3147 0)
				)
			)
			(stroke
				(width 0)
				(type default)
			)
			(fill no)
			(layer "B.CrtYd")
		)
		(fp_poly
			(pts
				(arc
					(start 3.0607 0)
					(mid -3.0607 0)
					(end 3.0607 0)
				)
			)
			(stroke
				(width 0)
				(type default)
			)
			(fill no)
			(layer "F.CrtYd")
		)
		(fp_poly
			(pts
				(arc
					(start 3.3147 0)
					(mid -3.3147 0)
					(end 3.3147 0)
				)
			)
			(stroke
				(width 0)
				(type default)
			)
			(fill no)
			(layer "B.Fab")
		)
		(fp_poly
			(pts
				(arc
					(start 3.0607 0)
					(mid -3.0607 0)
					(end 3.0607 0)
				)
			)
			(stroke
				(width 0)
				(type default)
			)
			(fill no)
			(layer "F.Fab")
		)
		(pad "1" thru_hole circle
			(at 0 0)
			(size 5.5118 5.5118)
			(drill 4.2164)
			(layers "*.Cu" "*.Mask")
			(remove_unused_layers no)
			(net "GND")
			(clearance -0.1397)
			(thermal_gap 0.3048)
			(padstack
				(mode front_inner_back)
				(layer "Inner"
					(shape circle)
					(size 4.6228 4.6228)
					(clearance 0.3048)
				)
				(layer "B.Cu"
					(shape circle)
					(size 6.0198 6.0198)
					(clearance -0.3937)
				)
			)
		)
	)
	(footprint ""
		(layer "F.Cu")
		(at 91.059 -7.493 90)
		(property "Reference" "R149"
			(at 0 0 90)
			(layer "F.SilkS")
			(hide yes)
			(effects
				(font
					(size 1.27 1.27)
				)
			)
		)
		(property "Value" "200KR2F-L-GP"
			(at 0.064008 -3.993896 90)
			(unlocked yes)
			(layer "F.Fab")
			(hide yes)
			(effects
				(font
					(size 1.016 1.016)
					(thickness 0.1524)
				)
			)
		)
		(property "Device Type" "R402H16"
			(at 0.064008 -5.517896 90)
			(unlocked yes)
			(layer "F.Fab")
			(hide yes)
			(effects
				(font
					(size 1.016 1.016)
					(thickness 0.1524)
				)
			)
		)
		(duplicate_pad_numbers_are_jumpers no)
		(fp_line
			(start 0.508 -0.9398)
			(end -0.508 -0.9398)
			(stroke
				(width 0.1524)
				(type default)
			)
			(layer "F.SilkS")
		)
		(fp_line
			(start -0.508 -0.9398)
			(end -0.508 0.9398)
			(stroke
				(width 0.1524)
				(type default)
			)
			(layer "F.SilkS")
		)
		(fp_rect
			(start -0.508 0.9398)
			(end 0.508 -0.9398)
			(stroke
				(width 0)
				(type default)
			)
			(fill no)
			(layer "F.CrtYd")
		)
		(fp_rect
			(start -0.508 0.9398)
			(end 0.508 -0.9398)
			(stroke
				(width 0)
				(type default)
			)
			(fill no)
			(layer "F.Fab")
		)
		(pad "1" smd custom
			(at 0 -0.4445 90)
			(size 0.1397 0.1397)
			(layers "F.Cu" "F.Mask" "F.Paste")
			(net "SW_SW_L_0")
			(options
				(clearance outline)
				(anchor circle)
			)
			(primitives
				(gr_poly
					(pts
						(arc
							(start -0.1778 -0.2794)
							(mid -0.249642 -0.249642)
							(end -0.2794 -0.1778)
						)
						(arc
							(start -0.2794 0.1778)
							(mid -0.249642 0.249642)
							(end -0.1778 0.2794)
						)
						(arc
							(start 0.1778 0.2794)
							(mid 0.249642 0.249642)
							(end 0.2794 0.1778)
						)
						(arc
							(start 0.2794 -0.1778)
							(mid 0.249642 -0.249642)
							(end 0.1778 -0.2794)
						)
					)
					(width 0)
					(fill yes)
				)
			)
		)
		(pad "2" smd custom
			(at 0 0.4445 90)
			(size 0.1397 0.1397)
			(layers "F.Cu" "F.Mask" "F.Paste")
			(net "SW_SW_L_N_0")
			(options
				(clearance outline)
				(anchor circle)
			)
			(primitives
				(gr_poly
					(pts
						(arc
							(start -0.1778 -0.2794)
							(mid -0.249642 -0.249642)
							(end -0.2794 -0.1778)
						)
						(arc
							(start -0.2794 0.1778)
							(mid -0.249642 0.249642)
							(end -0.1778 0.2794)
						)
						(arc
							(start 0.1778 0.2794)
							(mid 0.249642 0.249642)
							(end 0.2794 0.1778)
						)
						(arc
							(start 0.2794 -0.1778)
							(mid 0.249642 -0.249642)
							(end 0.1778 -0.2794)
						)
					)
					(width 0)
					(fill yes)
				)
			)
		)
	)
	(footprint ""
		(layer "F.Cu")
		(at 128.744472 -40.966644)
		(property "Reference" "R1"
			(at 0 0 0)
			(layer "F.SilkS")
			(hide yes)
			(effects
				(font
					(size 1.27 1.27)
				)
			)
		)
		(property "Value" "10KR2J-3-GP"
			(at 0.064008 -3.993896 0)
			(unlocked yes)
			(layer "F.Fab")
			(hide yes)
			(effects
				(font
					(size 1.016 1.016)
					(thickness 0.1524)
				)
			)
		)
		(property "Device Type" "R402H16"
			(at 0.064008 -5.517896 0)
			(unlocked yes)
			(layer "F.Fab")
			(hide yes)
			(effects
				(font
					(size 1.016 1.016)
					(thickness 0.1524)
				)
			)
		)
		(duplicate_pad_numbers_are_jumpers no)
		(fp_line
			(start -0.508 -0.9398)
			(end -0.508 0.9398)
			(stroke
				(width 0.1524)
				(type default)
			)
			(layer "F.SilkS")
		)
		(fp_line
			(start 0.508 -0.9398)
			(end -0.508 -0.9398)
			(stroke
				(width 0.1524)
				(type default)
			)
			(layer "F.SilkS")
		)
		(fp_rect
			(start -0.508 0.9398)
			(end 0.508 -0.9398)
			(stroke
				(width 0)
				(type default)
			)
			(fill no)
			(layer "F.CrtYd")
		)
		(fp_rect
			(start -0.508 0.9398)
			(end 0.508 -0.9398)
			(stroke
				(width 0)
				(type default)
			)
			(fill no)
			(layer "F.Fab")
		)
		(pad "1" smd custom
			(at 0 -0.4445)
			(size 0.1397 0.1397)
			(layers "F.Cu" "F.Mask" "F.Paste")
			(net "P3V3")
			(options
				(clearance outline)
				(anchor circle)
			)
			(primitives
				(gr_poly
					(pts
						(arc
							(start -0.1778 -0.2794)
							(mid -0.249642 -0.249642)
							(end -0.2794 -0.1778)
						)
						(arc
							(start -0.2794 0.1778)
							(mid -0.249642 0.249642)
							(end -0.1778 0.2794)
						)
						(arc
							(start 0.1778 0.2794)
							(mid 0.249642 0.249642)
							(end 0.2794 0.1778)
						)
						(arc
							(start 0.2794 -0.1778)
							(mid 0.249642 -0.249642)
							(end 0.1778 -0.2794)
						)
					)
					(width 0)
					(fill yes)
				)
			)
		)
		(pad "2" smd custom
			(at 0 0.4445)
			(size 0.1397 0.1397)
			(layers "F.Cu" "F.Mask" "F.Paste")
			(net "HBA_PRSNT1_N")
			(options
				(clearance outline)
				(anchor circle)
			)
			(primitives
				(gr_poly
					(pts
						(arc
							(start -0.1778 -0.2794)
							(mid -0.249642 -0.249642)
							(end -0.2794 -0.1778)
						)
						(arc
							(start -0.2794 0.1778)
							(mid -0.249642 0.249642)
							(end -0.1778 0.2794)
						)
						(arc
							(start 0.1778 0.2794)
							(mid 0.249642 0.249642)
							(end 0.2794 0.1778)
						)
						(arc
							(start 0.2794 -0.1778)
							(mid 0.249642 -0.249642)
							(end 0.1778 -0.2794)
						)
					)
					(width 0)
					(fill yes)
				)
			)
		)
	)
	(footprint ""
		(layer "F.Cu")
		(at 11.811 -20.193 -90)
		(property "Reference" "C26"
			(at 0 0 270)
			(layer "F.SilkS")
			(hide yes)
			(effects
				(font
					(size 1.27 1.27)
				)
			)
		)
		(property "Value" "SCD1U25V2KX-GP"
			(at 1.1811 -2.7051 270)
			(unlocked yes)
			(layer "F.Fab")
			(hide yes)
			(effects
				(font
					(size 1.016 1.016)
					(thickness 0.1524)
				)
			)
		)
		(property "Device Type" "C402H22"
			(at 1.1811 -4.2291 270)
			(unlocked yes)
			(layer "F.Fab")
			(hide yes)
			(effects
				(font
					(size 1.016 1.016)
					(thickness 0.1524)
				)
			)
		)
		(duplicate_pad_numbers_are_jumpers no)
		(fp_rect
			(start -0.4318 0.9525)
			(end 0.4318 -0.9525)
			(stroke
				(width 0)
				(type default)
			)
			(fill no)
			(layer "F.CrtYd")
		)
		(fp_rect
			(start -0.4318 0.9525)
			(end 0.4318 -0.9525)
			(stroke
				(width 0)
				(type default)
			)
			(fill no)
			(layer "F.Fab")
		)
		(pad "1" smd custom
			(at 0 -0.4445 270)
			(size 0.1524 0.1524)
			(layers "F.Cu" "F.Mask" "F.Paste")
			(net "P5V")
			(options
				(clearance outline)
				(anchor circle)
			)
			(primitives
				(gr_poly
					(pts
						(arc
							(start 0.3048 -0.2032)
							(mid 0.275042 -0.275042)
							(end 0.2032 -0.3048)
						)
						(arc
							(start -0.2032 -0.3048)
							(mid -0.275042 -0.275042)
							(end -0.3048 -0.2032)
						)
						(arc
							(start -0.3048 0.2032)
							(mid -0.275042 0.275042)
							(end -0.2032 0.3048)
						)
						(arc
							(start 0.2032 0.3048)
							(mid 0.275042 0.275042)
							(end 0.3048 0.2032)
						)
					)
					(width 0)
					(fill yes)
				)
			)
		)
		(pad "2" smd custom
			(at 0 0.4445 270)
			(size 0.1524 0.1524)
			(layers "F.Cu" "F.Mask" "F.Paste")
			(net "GND")
			(options
				(clearance outline)
				(anchor circle)
			)
			(primitives
				(gr_poly
					(pts
						(arc
							(start 0.3048 -0.2032)
							(mid 0.275042 -0.275042)
							(end 0.2032 -0.3048)
						)
						(arc
							(start -0.2032 -0.3048)
							(mid -0.275042 -0.275042)
							(end -0.3048 -0.2032)
						)
						(arc
							(start -0.3048 0.2032)
							(mid -0.275042 0.275042)
							(end -0.2032 0.3048)
						)
						(arc
							(start 0.2032 0.3048)
							(mid 0.275042 0.275042)
							(end 0.3048 0.2032)
						)
					)
					(width 0)
					(fill yes)
				)
			)
		)
	)
	(footprint ""
		(layer "F.Cu")
		(at 77.978 -8.128 90)
		(property "Reference" "R153"
			(at 0 0 90)
			(layer "F.SilkS")
			(hide yes)
			(effects
				(font
					(size 1.27 1.27)
				)
			)
		)
		(property "Value" "33KR2J-3-GP"
			(at 0.064008 -3.993896 90)
			(unlocked yes)
			(layer "F.Fab")
			(hide yes)
			(effects
				(font
					(size 1.016 1.016)
					(thickness 0.1524)
				)
			)
		)
		(property "Device Type" "R402H16"
			(at 0.064008 -5.517896 90)
			(unlocked yes)
			(layer "F.Fab")
			(hide yes)
			(effects
				(font
					(size 1.016 1.016)
					(thickness 0.1524)
				)
			)
		)
		(duplicate_pad_numbers_are_jumpers no)
		(fp_line
			(start 0.508 -0.9398)
			(end -0.508 -0.9398)
			(stroke
				(width 0.1524)
				(type default)
			)
			(layer "F.SilkS")
		)
		(fp_line
			(start -0.508 -0.9398)
			(end -0.508 0.9398)
			(stroke
				(width 0.1524)
				(type default)
			)
			(layer "F.SilkS")
		)
		(fp_rect
			(start -0.508 0.9398)
			(end 0.508 -0.9398)
			(stroke
				(width 0)
				(type default)
			)
			(fill no)
			(layer "F.CrtYd")
		)
		(fp_rect
			(start -0.508 0.9398)
			(end 0.508 -0.9398)
			(stroke
				(width 0)
				(type default)
			)
			(fill no)
			(layer "F.Fab")
		)
		(pad "1" smd custom
			(at 0 -0.4445 90)
			(size 0.1397 0.1397)
			(layers "F.Cu" "F.Mask" "F.Paste")
			(net "PWR_EN_L")
			(options
				(clearance outline)
				(anchor circle)
			)
			(primitives
				(gr_poly
					(pts
						(arc
							(start -0.1778 -0.2794)
							(mid -0.249642 -0.249642)
							(end -0.2794 -0.1778)
						)
						(arc
							(start -0.2794 0.1778)
							(mid -0.249642 0.249642)
							(end -0.1778 0.2794)
						)
						(arc
							(start 0.1778 0.2794)
							(mid 0.249642 0.249642)
							(end 0.2794 0.1778)
						)
						(arc
							(start 0.2794 -0.1778)
							(mid 0.249642 -0.249642)
							(end 0.1778 -0.2794)
						)
					)
					(width 0)
					(fill yes)
				)
			)
		)
		(pad "2" smd custom
			(at 0 0.4445 90)
			(size 0.1397 0.1397)
			(layers "F.Cu" "F.Mask" "F.Paste")
			(net "VIN_P3")
			(options
				(clearance outline)
				(anchor circle)
			)
			(primitives
				(gr_poly
					(pts
						(arc
							(start -0.1778 -0.2794)
							(mid -0.249642 -0.249642)
							(end -0.2794 -0.1778)
						)
						(arc
							(start -0.2794 0.1778)
							(mid -0.249642 0.249642)
							(end -0.1778 0.2794)
						)
						(arc
							(start 0.1778 0.2794)
							(mid 0.249642 0.249642)
							(end 0.2794 0.1778)
						)
						(arc
							(start 0.2794 -0.1778)
							(mid 0.249642 -0.249642)
							(end 0.1778 -0.2794)
						)
					)
					(width 0)
					(fill yes)
				)
			)
		)
	)
	(footprint ""
		(layer "F.Cu")
		(at 83.096354 -38.56736 180)
		(property "Reference" "R139"
			(at 0 0 180)
			(layer "F.SilkS")
			(hide yes)
			(effects
				(font
					(size 1.27 1.27)
				)
			)
		)
		(property "Value" "300KR2F-GP"
			(at 0.064008 -3.993896 180)
			(unlocked yes)
			(layer "F.Fab")
			(hide yes)
			(effects
				(font
					(size 1.016 1.016)
					(thickness 0.1524)
				)
			)
		)
		(property "Device Type" "R402H16"
			(at 0.064008 -5.517896 180)
			(unlocked yes)
			(layer "F.Fab")
			(hide yes)
			(effects
				(font
					(size 1.016 1.016)
					(thickness 0.1524)
				)
			)
		)
		(duplicate_pad_numbers_are_jumpers no)
		(fp_line
			(start 0.508 -0.9398)
			(end -0.508 -0.9398)
			(stroke
				(width 0.1524)
				(type default)
			)
			(layer "F.SilkS")
		)
		(fp_line
			(start -0.508 -0.9398)
			(end -0.508 0.9398)
			(stroke
				(width 0.1524)
				(type default)
			)
			(layer "F.SilkS")
		)
		(fp_rect
			(start -0.508 0.9398)
			(end 0.508 -0.9398)
			(stroke
				(width 0)
				(type default)
			)
			(fill no)
			(layer "F.CrtYd")
		)
		(fp_rect
			(start -0.508 0.9398)
			(end 0.508 -0.9398)
			(stroke
				(width 0)
				(type default)
			)
			(fill no)
			(layer "F.Fab")
		)
		(pad "1" smd custom
			(at 0 -0.4445 180)
			(size 0.1397 0.1397)
			(layers "F.Cu" "F.Mask" "F.Paste")
			(net "SW_SW_R_N_0")
			(options
				(clearance outline)
				(anchor circle)
			)
			(primitives
				(gr_poly
					(pts
						(arc
							(start -0.1778 -0.2794)
							(mid -0.249642 -0.249642)
							(end -0.2794 -0.1778)
						)
						(arc
							(start -0.2794 0.1778)
							(mid -0.249642 0.249642)
							(end -0.1778 0.2794)
						)
						(arc
							(start 0.1778 0.2794)
							(mid 0.249642 0.249642)
							(end 0.2794 0.1778)
						)
						(arc
							(start 0.2794 -0.1778)
							(mid 0.249642 -0.249642)
							(end 0.1778 -0.2794)
						)
					)
					(width 0)
					(fill yes)
				)
			)
		)
		(pad "2" smd custom
			(at 0 0.4445 180)
			(size 0.1397 0.1397)
			(layers "F.Cu" "F.Mask" "F.Paste")
			(net "P12V")
			(options
				(clearance outline)
				(anchor circle)
			)
			(primitives
				(gr_poly
					(pts
						(arc
							(start -0.1778 -0.2794)
							(mid -0.249642 -0.249642)
							(end -0.2794 -0.1778)
						)
						(arc
							(start -0.2794 0.1778)
							(mid -0.249642 0.249642)
							(end -0.1778 0.2794)
						)
						(arc
							(start 0.1778 0.2794)
							(mid 0.249642 0.249642)
							(end 0.2794 0.1778)
						)
						(arc
							(start 0.2794 -0.1778)
							(mid 0.249642 -0.249642)
							(end 0.1778 -0.2794)
						)
					)
					(width 0)
					(fill yes)
				)
			)
		)
	)
	(footprint ""
		(layer "F.Cu")
		(at 59.46902 -19.523456 90)
		(property "Reference" "C19"
			(at 0 0 90)
			(layer "F.SilkS")
			(hide yes)
			(effects
				(font
					(size 1.27 1.27)
				)
			)
		)
		(property "Value" "SC10U25V6KX-1GP"
			(at -0.0762 -5.1308 90)
			(unlocked yes)
			(layer "F.Fab")
			(hide yes)
			(effects
				(font
					(size 1.016 1.016)
					(thickness 0.1524)
				)
			)
		)
		(property "Device Type" "C1206H71"
			(at -0.127 -6.6548 90)
			(unlocked yes)
			(layer "F.Fab")
			(hide yes)
			(effects
				(font
					(size 1.016 1.016)
					(thickness 0.1524)
				)
			)
		)
		(duplicate_pad_numbers_are_jumpers no)
		(fp_line
			(start 1.016 -2.2352)
			(end 1.016 -0.8382)
			(stroke
				(width 0.1524)
				(type default)
			)
			(layer "F.SilkS")
		)
		(fp_line
			(start -1.016 -2.2352)
			(end 1.016 -2.2352)
			(stroke
				(width 0.1524)
				(type default)
			)
			(layer "F.SilkS")
		)
		(fp_line
			(start -1.016 -0.8382)
			(end -1.016 -2.2352)
			(stroke
				(width 0.1524)
				(type default)
			)
			(layer "F.SilkS")
		)
		(fp_line
			(start 1.016 0.8382)
			(end 1.016 2.2352)
			(stroke
				(width 0.1524)
				(type default)
			)
			(layer "F.SilkS")
		)
		(fp_line
			(start 1.016 2.2352)
			(end -1.016 2.2352)
			(stroke
				(width 0.1524)
				(type default)
			)
			(layer "F.SilkS")
		)
		(fp_line
			(start -1.016 2.2352)
			(end -1.016 0.8382)
			(stroke
				(width 0.1524)
				(type default)
			)
			(layer "F.SilkS")
		)
		(fp_rect
			(start -1.0922 2.3114)
			(end 1.0922 -2.3114)
			(stroke
				(width 0)
				(type default)
			)
			(fill no)
			(layer "F.CrtYd")
		)
		(fp_poly
			(pts
				(xy 1.0922 -2.3114) (xy 1.0922 2.3114) (xy -1.0922 2.3114) (xy -1.0922 -2.3114)
			)
			(stroke
				(width 0)
				(type default)
			)
			(fill no)
			(layer "F.Fab")
		)
		(pad "1" smd rect
			(at 0 -1.397 90)
			(size 1.651 1.27)
			(layers "F.Cu" "F.Mask" "F.Paste")
			(net "P12V_SW_L")
		)
		(pad "2" smd rect
			(at 0 1.397 90)
			(size 1.651 1.27)
			(layers "F.Cu" "F.Mask" "F.Paste")
			(net "GND")
		)
	)
)
